(kicad_pcb
	(version 20260206)
	(generator "pcbnew")
	(generator_version "10.0")
	(general
		(thickness 1.6)
		(legacy_teardrops no)
	)
	(paper "A4")
	(title_block
		(title "baseboard — 13948-1b.1110WZS1818.brd")
		(comment 1 "Honey Badger (Wiwynn) / footprints 470-472 of 2523")
	)
	(layers
		(0 "F.Cu" signal "TOP")
		(4 "In1.Cu" signal "L2GND")
		(6 "In2.Cu" signal "L3")
		(8 "In3.Cu" signal "L4VCC")
		(10 "In4.Cu" signal "L5VCC")
		(12 "In5.Cu" signal "L6")
		(14 "In6.Cu" signal "L7GND")
		(2 "B.Cu" signal "BOTTOM")
		(9 "F.Adhes" user "F.Adhesive")
		(11 "B.Adhes" user "B.Adhesive")
		(13 "F.Paste" user "Package Geometry/Pastemask Top")
		(15 "B.Paste" user "Package Geometry/Pastemask Bottom")
		(5 "F.SilkS" user "Ref Des/Silkscreen Top")
		(7 "B.SilkS" user "Ref Des/Silkscreen Bottom")
		(1 "F.Mask" user "Board Geometry/Soldermask Top")
		(3 "B.Mask" user "Board Geometry/Soldermask Bottom")
		(17 "Dwgs.User" user "User.Drawings")
		(19 "Cmts.User" user "User.Comments")
		(21 "Eco1.User" user "User.Eco1")
		(23 "Eco2.User" user "User.Eco2")
		(25 "Edge.Cuts" user "Board Geometry/Outline")
		(27 "Margin" user)
		(31 "F.CrtYd" user "Package Geometry/Place Bound Top")
		(29 "B.CrtYd" user "Package Geometry/Place Bound Bottom")
		(35 "F.Fab" user "Ref Des/Assembly Top")
		(33 "B.Fab" user "Ref Des/Assembly Bottom")
	)
	(footprint ""
		(layer "F.Cu")
		(at 157.459934 -11.210036)
		(property "Reference" "RJ1"
			(at 0 0 0)
			(layer "F.SilkS")
			(hide yes)
			(effects
				(font
					(size 1.27 1.27)
				)
			)
		)
		(property "Value" "RJ45-LED-12P-10-GP"
			(at -2.15773 -12.96797 0)
			(unlocked yes)
			(layer "F.Fab")
			(hide yes)
			(effects
				(font
					(size 1.016 1.016)
					(thickness 0.1524)
				)
			)
		)
		(property "Device Type" "XRJH-01H-D-H71-D81-W"
			(at -2.15773 -14.49197 0)
			(unlocked yes)
			(layer "F.Fab")
			(hide yes)
			(effects
				(font
					(size 1.016 1.016)
					(thickness 0.1524)
				)
			)
		)
		(duplicate_pad_numbers_are_jumpers no)
		(fp_line
			(start -10.033 -1.2446)
			(end -9.144 -1.2446)
			(stroke
				(width 0.1524)
				(type default)
			)
			(layer "F.SilkS")
		)
		(fp_line
			(start -10.033 1.2446)
			(end -10.033 -1.2446)
			(stroke
				(width 0.1524)
				(type default)
			)
			(layer "F.SilkS")
		)
		(fp_line
			(start -9.144 -11.176)
			(end 9.144 -11.176)
			(stroke
				(width 0.1524)
				(type default)
			)
			(layer "F.SilkS")
		)
		(fp_line
			(start -9.144 -1.2446)
			(end -9.144 -11.176)
			(stroke
				(width 0.1524)
				(type default)
			)
			(layer "F.SilkS")
		)
		(fp_line
			(start -9.144 1.2446)
			(end -10.033 1.2446)
			(stroke
				(width 0.1524)
				(type default)
			)
			(layer "F.SilkS")
		)
		(fp_line
			(start -9.144 13.462)
			(end -9.144 1.2446)
			(stroke
				(width 0.1524)
				(type default)
			)
			(layer "F.SilkS")
		)
		(fp_line
			(start 9.144 -11.176)
			(end 9.144 -1.2446)
			(stroke
				(width 0.1524)
				(type default)
			)
			(layer "F.SilkS")
		)
		(fp_line
			(start 9.144 -1.2446)
			(end 10.033 -1.2446)
			(stroke
				(width 0.1524)
				(type default)
			)
			(layer "F.SilkS")
		)
		(fp_line
			(start 9.144 1.2446)
			(end 9.144 13.462)
			(stroke
				(width 0.1524)
				(type default)
			)
			(layer "F.SilkS")
		)
		(fp_line
			(start 9.144 13.462)
			(end -9.144 13.462)
			(stroke
				(width 0.1524)
				(type default)
			)
			(layer "F.SilkS")
		)
		(fp_line
			(start 10.033 -1.2446)
			(end 10.033 1.2446)
			(stroke
				(width 0.1524)
				(type default)
			)
			(layer "F.SilkS")
		)
		(fp_line
			(start 10.033 1.2446)
			(end 9.144 1.2446)
			(stroke
				(width 0.1524)
				(type default)
			)
			(layer "F.SilkS")
		)
		(fp_circle
			(center -8.789924 0)
			(end -7.443724 0)
			(stroke
				(width 0.3048)
				(type default)
			)
			(fill no)
			(layer "F.SilkS")
		)
		(fp_circle
			(center -7.519924 6.35)
			(end -6.326124 6.35)
			(stroke
				(width 0.3048)
				(type default)
			)
			(fill no)
			(layer "F.SilkS")
		)
		(fp_circle
			(center -7.519924 8.89)
			(end -6.326124 8.89)
			(stroke
				(width 0.3048)
				(type default)
			)
			(fill no)
			(layer "F.SilkS")
		)
		(fp_circle
			(center -6.100064 -9.139936)
			(end -5.084064 -9.139936)
			(stroke
				(width 0.3048)
				(type default)
			)
			(fill no)
			(layer "F.SilkS")
		)
		(fp_circle
			(center -5.07492 -6.599936)
			(end -4.05892 -6.599936)
			(stroke
				(width 0.3048)
				(type default)
			)
			(fill no)
			(layer "F.SilkS")
		)
		(fp_circle
			(center -4.070096 -9.139936)
			(end -3.054096 -9.139936)
			(stroke
				(width 0.3048)
				(type default)
			)
			(fill no)
			(layer "F.SilkS")
		)
		(fp_circle
			(center -3.044952 -6.599936)
			(end -2.028952 -6.599936)
			(stroke
				(width 0.3048)
				(type default)
			)
			(fill no)
			(layer "F.SilkS")
		)
		(fp_circle
			(center -2.040128 -9.139936)
			(end -1.024128 -9.139936)
			(stroke
				(width 0.3048)
				(type default)
			)
			(fill no)
			(layer "F.SilkS")
		)
		(fp_circle
			(center -1.014984 -6.599936)
			(end 0.001016 -6.599936)
			(stroke
				(width 0.3048)
				(type default)
			)
			(fill no)
			(layer "F.SilkS")
		)
		(fp_circle
			(center 1.014984 -6.599936)
			(end 2.030984 -6.599936)
			(stroke
				(width 0.3048)
				(type default)
			)
			(fill no)
			(layer "F.SilkS")
		)
		(fp_circle
			(center 2.040128 -9.139936)
			(end 3.056128 -9.139936)
			(stroke
				(width 0.3048)
				(type default)
			)
			(fill no)
			(layer "F.SilkS")
		)
		(fp_circle
			(center 3.044952 -6.599936)
			(end 4.060952 -6.599936)
			(stroke
				(width 0.3048)
				(type default)
			)
			(fill no)
			(layer "F.SilkS")
		)
		(fp_circle
			(center 4.070096 -9.139936)
			(end 5.086096 -9.139936)
			(stroke
				(width 0.3048)
				(type default)
			)
			(fill no)
			(layer "F.SilkS")
		)
		(fp_circle
			(center 5.07492 -6.599936)
			(end 6.09092 -6.599936)
			(stroke
				(width 0.3048)
				(type default)
			)
			(fill no)
			(layer "F.SilkS")
		)
		(fp_circle
			(center 6.100064 -9.139936)
			(end 7.116064 -9.139936)
			(stroke
				(width 0.3048)
				(type default)
			)
			(fill no)
			(layer "F.SilkS")
		)
		(fp_circle
			(center 7.519924 3.81)
			(end 8.713724 3.81)
			(stroke
				(width 0.3048)
				(type default)
			)
			(fill no)
			(layer "F.SilkS")
		)
		(fp_circle
			(center 7.519924 6.35)
			(end 8.713724 6.35)
			(stroke
				(width 0.3048)
				(type default)
			)
			(fill no)
			(layer "F.SilkS")
		)
		(fp_circle
			(center 7.519924 8.89)
			(end 8.713724 8.89)
			(stroke
				(width 0.3048)
				(type default)
			)
			(fill no)
			(layer "F.SilkS")
		)
		(fp_circle
			(center 8.789924 0)
			(end 10.136124 0)
			(stroke
				(width 0.3048)
				(type default)
			)
			(fill no)
			(layer "F.SilkS")
		)
		(fp_rect
			(start -8.89 13.208)
			(end 8.89 -10.922)
			(stroke
				(width 0)
				(type default)
			)
			(fill no)
			(layer "F.CrtYd")
		)
		(fp_poly
			(pts
				(xy -9.398 13.716) (xy -9.398 1.4986) (xy -10.287 1.4986) (xy -10.287 -1.4986) (xy -9.398 -1.4986)
				(xy -9.398 -11.43) (xy 9.398 -11.43) (xy 9.398 -1.4986) (xy 10.287 -1.4986) (xy 10.287 -0.00635)
				(xy 8.89 -0.00635) (xy 8.89 -10.922) (xy -8.89 -10.922) (xy -8.89 13.208) (xy 8.89 13.208) (xy 8.89 0.00635)
				(xy 10.287 0.00635) (xy 10.287 1.4986) (xy 9.398 1.4986) (xy 9.398 13.716)
			)
			(stroke
				(width 0)
				(type default)
			)
			(fill no)
			(layer "F.CrtYd")
		)
		(fp_poly
			(pts
				(xy -9.398 13.716) (xy -9.398 1.4986) (xy -10.287 1.4986) (xy -10.287 -1.4986) (xy -9.398 -1.4986)
				(xy -9.398 -11.43) (xy 9.398 -11.43) (xy 9.398 -1.4986) (xy 10.287 -1.4986) (xy 10.287 1.4986) (xy 9.398 1.4986)
				(xy 9.398 13.716)
			)
			(stroke
				(width 0)
				(type default)
			)
			(fill no)
			(layer "F.Fab")
		)
		(pad "" np_thru_hole circle
			(at -4.824984 0)
			(size 0.254 0.254)
			(drill 3.2512)
			(layers "*.Cu" "*.Mask")
			(clearance 1.8542)
			(thermal_gap 1.8542)
		)
		(pad "" np_thru_hole circle
			(at 4.824984 0)
			(size 0.254 0.254)
			(drill 3.2512)
			(layers "*.Cu" "*.Mask")
			(clearance 1.8542)
			(thermal_gap 1.8542)
		)
		(pad "1" thru_hole circle
			(at 5.07492 -6.599936)
			(size 1.3208 1.3208)
			(drill 0.9144)
			(layers "*.Cu" "*.Mask")
			(remove_unused_layers no)
			(net "RJ45_GND_1")
			(clearance 0.1524)
			(thermal_gap 0.1524)
		)
		(pad "2" thru_hole circle
			(at 3.044952 -6.599936)
			(size 1.3208 1.3208)
			(drill 0.9144)
			(layers "*.Cu" "*.Mask")
			(remove_unused_layers no)
			(net "TP_LAN_5")
			(clearance 0.1524)
			(thermal_gap 0.1524)
		)
		(pad "3" thru_hole circle
			(at 1.014984 -6.599936)
			(size 1.3208 1.3208)
			(drill 0.9144)
			(layers "*.Cu" "*.Mask")
			(remove_unused_layers no)
			(net "TP_LAN_7")
			(clearance 0.1524)
			(thermal_gap 0.1524)
		)
		(pad "4" thru_hole circle
			(at -1.014984 -6.599936)
			(size 1.3208 1.3208)
			(drill 0.9144)
			(layers "*.Cu" "*.Mask")
			(remove_unused_layers no)
			(net "BCM5221_MB_RX_DP")
			(clearance 0.1524)
			(thermal_gap 0.1524)
		)
		(pad "5" thru_hole circle
			(at -3.044952 -6.599936)
			(size 1.3208 1.3208)
			(drill 0.9144)
			(layers "*.Cu" "*.Mask")
			(remove_unused_layers no)
			(net "BCM5221_MB_RX_DN")
			(clearance 0.1524)
			(thermal_gap 0.1524)
		)
		(pad "6" thru_hole circle
			(at -5.07492 -6.599936)
			(size 1.3208 1.3208)
			(drill 0.9144)
			(layers "*.Cu" "*.Mask")
			(remove_unused_layers no)
			(net "PHY_AVDD")
			(clearance 0.1524)
			(thermal_gap 0.1524)
		)
		(pad "7" thru_hole circle
			(at 6.100064 -9.139936)
			(size 1.3208 1.3208)
			(drill 0.9144)
			(layers "*.Cu" "*.Mask")
			(remove_unused_layers no)
			(net "RJ45_GND_7")
			(clearance 0.1524)
			(thermal_gap 0.1524)
		)
		(pad "8" thru_hole circle
			(at 4.070096 -9.139936)
			(size 1.3208 1.3208)
			(drill 0.9144)
			(layers "*.Cu" "*.Mask")
			(remove_unused_layers no)
			(net "TP_LAN_4")
			(clearance 0.1524)
			(thermal_gap 0.1524)
		)
		(pad "9" thru_hole circle
			(at 2.040128 -9.139936)
			(size 1.3208 1.3208)
			(drill 0.9144)
			(layers "*.Cu" "*.Mask")
			(remove_unused_layers no)
			(net "TP_LAN_6")
			(clearance 0.1524)
			(thermal_gap 0.1524)
		)
		(pad "10" thru_hole circle
			(at -2.040128 -9.139936)
			(size 1.3208 1.3208)
			(drill 0.9144)
			(layers "*.Cu" "*.Mask")
			(remove_unused_layers no)
			(net "BCM5221_MB_TX_DN")
			(clearance 0.1524)
			(thermal_gap 0.1524)
		)
		(pad "11" thru_hole circle
			(at -4.070096 -9.139936)
			(size 1.3208 1.3208)
			(drill 0.9144)
			(layers "*.Cu" "*.Mask")
			(remove_unused_layers no)
			(net "BCM5221_MB_TX_DP")
			(clearance 0.1524)
			(thermal_gap 0.1524)
		)
		(pad "12" thru_hole circle
			(at -6.100064 -9.139936)
			(size 1.3208 1.3208)
			(drill 0.9144)
			(layers "*.Cu" "*.Mask")
			(remove_unused_layers no)
			(net "PHY_AVDD")
			(clearance 0.1524)
			(thermal_gap 0.1524)
		)
		(pad "13" thru_hole circle
			(at 8.789924 0)
			(size 1.9812 1.9812)
			(drill 1.5748)
			(layers "*.Cu" "*.Mask")
			(remove_unused_layers no)
			(net "GND")
			(clearance 0.1524)
			(thermal_gap 0.1524)
		)
		(pad "14" thru_hole circle
			(at -8.789924 0)
			(size 1.9812 1.9812)
			(drill 1.5748)
			(layers "*.Cu" "*.Mask")
			(remove_unused_layers no)
			(net "GND")
			(clearance 0.1524)
			(thermal_gap 0.1524)
		)
		(pad "D1" thru_hole circle
			(at -7.519924 6.35)
			(size 1.6764 1.6764)
			(drill 1.27)
			(layers "*.Cu" "*.Mask")
			(remove_unused_layers no)
			(net "PHY_ACTLED_N")
			(clearance 0.1524)
			(thermal_gap 0.1524)
		)
		(pad "D2" thru_hole circle
			(at -7.519924 8.89)
			(size 1.6764 1.6764)
			(drill 1.27)
			(layers "*.Cu" "*.Mask")
			(remove_unused_layers no)
			(net "LED_MDI0_ACT")
			(clearance 0.1524)
			(thermal_gap 0.1524)
		)
		(pad "D3" thru_hole circle
			(at 7.519924 3.81)
			(size 1.6764 1.6764)
			(drill 1.27)
			(layers "*.Cu" "*.Mask")
			(remove_unused_layers no)
			(net "Net_2092")
			(clearance 0.1524)
			(thermal_gap 0.1524)
		)
		(pad "D4" thru_hole circle
			(at 7.519924 6.35)
			(size 1.6764 1.6764)
			(drill 1.27)
			(layers "*.Cu" "*.Mask")
			(remove_unused_layers no)
			(net "LED_MDI0_LINK")
			(clearance 0.1524)
			(thermal_gap 0.1524)
		)
		(pad "D5" thru_hole circle
			(at 7.519924 8.89)
			(size 1.6764 1.6764)
			(drill 1.27)
			(layers "*.Cu" "*.Mask")
			(remove_unused_layers no)
			(net "PHY_LNKLED_N")
			(clearance 0.1524)
			(thermal_gap 0.1524)
		)
		(zone
			(layer "F.Cu")
			(hatch none 0.5)
			(connect_pads
				(clearance 0)
			)
			(min_thickness 0.25)
			(keepout
				(tracks allowed)
				(vias not_allowed)
				(pads allowed)
				(copperpour not_allowed)
				(footprints allowed)
			)
			(placement
				(enabled no)
				(sheetname "")
			)
			(fill
				(thermal_gap 0.5)
				(thermal_bridge_width 0.5)
				(island_removal_mode 0)
			)
			(polygon
				(pts
					(xy 148.26996 -12.800076) (xy 148.26996 -15.40002) (xy 150.370032 -15.40002) (xy 150.370032 -12.800076)
				)
			)
		)
		(zone
			(layer "F.Cu")
			(hatch none 0.5)
			(connect_pads
				(clearance 0)
			)
			(min_thickness 0.25)
			(keepout
				(tracks not_allowed)
				(vias allowed)
				(pads allowed)
				(copperpour not_allowed)
				(footprints allowed)
			)
			(placement
				(enabled no)
				(sheetname "")
			)
			(fill
				(thermal_gap 0.5)
				(thermal_bridge_width 0.5)
				(island_removal_mode 0)
			)
			(polygon
				(pts
					(xy 148.26996 -12.800076) (xy 150.370032 -12.800076) (xy 150.370032 -15.40002) (xy 148.26996 -15.40002)
				)
			)
		)
		(zone
			(layer "F.Cu")
			(hatch none 0.5)
			(connect_pads
				(clearance 0)
			)
			(min_thickness 0.25)
			(keepout
				(tracks not_allowed)
				(vias allowed)
				(pads allowed)
				(copperpour not_allowed)
				(footprints allowed)
			)
			(placement
				(enabled no)
				(sheetname "")
			)
			(fill
				(thermal_gap 0.5)
				(thermal_bridge_width 0.5)
				(island_removal_mode 0)
			)
			(polygon
				(pts
					(xy 164.549836 -12.800076) (xy 166.649908 -12.800076) (xy 166.649908 -15.40002) (xy 164.549836 -15.40002)
				)
			)
		)
		(zone
			(layer "F.Cu")
			(hatch none 0.5)
			(connect_pads
				(clearance 0)
			)
			(min_thickness 0.25)
			(keepout
				(tracks allowed)
				(vias not_allowed)
				(pads allowed)
				(copperpour not_allowed)
				(footprints allowed)
			)
			(placement
				(enabled no)
				(sheetname "")
			)
			(fill
				(thermal_gap 0.5)
				(thermal_bridge_width 0.5)
				(island_removal_mode 0)
			)
			(polygon
				(pts
					(xy 166.649908 -12.800076) (xy 166.649908 -15.40002) (xy 164.549836 -15.40002) (xy 164.549836 -12.800076)
				)
			)
		)
		(zone
			(layer "F.Cu")
			(hatch none 0.5)
			(connect_pads
				(clearance 0)
			)
			(min_thickness 0.25)
			(keepout
				(tracks not_allowed)
				(vias allowed)
				(pads allowed)
				(copperpour not_allowed)
				(footprints allowed)
			)
			(placement
				(enabled no)
				(sheetname "")
			)
			(fill
				(thermal_gap 0.5)
				(thermal_bridge_width 0.5)
				(island_removal_mode 0)
			)
			(polygon
				(pts
					(xy 148.26996 2.29997) (xy 166.649908 2.29997) (xy 166.649908 -1.249934) (xy 164.141658 -1.249934)
					(xy 164.141658 -7.200138) (xy 150.77821 -7.200138) (xy 150.77821 -1.249934) (xy 148.26996 -1.249934)
				)
			)
		)
		(zone
			(layer "F.Cu")
			(hatch none 0.5)
			(connect_pads
				(clearance 0)
			)
			(min_thickness 0.25)
			(keepout
				(tracks allowed)
				(vias not_allowed)
				(pads allowed)
				(copperpour not_allowed)
				(footprints allowed)
			)
			(placement
				(enabled no)
				(sheetname "")
			)
			(fill
				(thermal_gap 0.5)
				(thermal_bridge_width 0.5)
				(island_removal_mode 0)
			)
			(polygon
				(pts
					(xy 148.26996 2.29997) (xy 166.649908 2.29997) (xy 166.649908 -1.249934) (xy 164.141658 -1.249934)
					(xy 164.141658 -7.200138) (xy 150.77821 -7.200138) (xy 150.77821 -1.249934) (xy 148.26996 -1.249934)
				)
			)
		)
		(zone
			(layers "F.Cu" "B.Cu" "In1.Cu" "In2.Cu" "In3.Cu" "In4.Cu" "In5.Cu" "In6.Cu")
			(hatch none 0.5)
			(connect_pads
				(clearance 0)
			)
			(min_thickness 0.25)
			(keepout
				(tracks not_allowed)
				(vias allowed)
				(pads allowed)
				(copperpour not_allowed)
				(footprints allowed)
			)
			(placement
				(enabled no)
				(sheetname "")
			)
			(fill
				(thermal_gap 0.5)
				(thermal_bridge_width 0.5)
				(island_removal_mode 0)
			)
			(polygon
				(pts
					(arc
						(start 154.56535 -11.210036)
						(mid 150.70455 -11.210036)
						(end 154.56535 -11.210036)
					)
				)
			)
		)
		(zone
			(layers "F.Cu" "B.Cu" "In1.Cu" "In2.Cu" "In3.Cu" "In4.Cu" "In5.Cu" "In6.Cu")
			(hatch none 0.5)
			(connect_pads
				(clearance 0)
			)
			(min_thickness 0.25)
			(keepout
				(tracks not_allowed)
				(vias allowed)
				(pads allowed)
				(copperpour not_allowed)
				(footprints allowed)
			)
			(placement
				(enabled no)
				(sheetname "")
			)
			(fill
				(thermal_gap 0.5)
				(thermal_bridge_width 0.5)
				(island_removal_mode 0)
			)
			(polygon
				(pts
					(arc
						(start 164.215318 -11.210036)
						(mid 160.354518 -11.210036)
						(end 164.215318 -11.210036)
					)
				)
			)
		)
	)
	(footprint ""
		(layer "F.Cu")
		(at 305.308 -182.88)
		(property "Reference" "TP114"
			(at 0 0 0)
			(layer "F.SilkS")
			(hide yes)
			(effects
				(font
					(size 1.27 1.27)
				)
			)
		)
		(property "Value" "TPAD28"
			(at 0.0127 -1.8034 0)
			(unlocked yes)
			(layer "F.Fab")
			(hide yes)
			(effects
				(font
					(size 1.016 1.016)
					(thickness 0.1524)
				)
			)
		)
		(property "Device Type" "TPAD28"
			(at 0.0127 -3.3274 0)
			(unlocked yes)
			(layer "F.Fab")
			(hide yes)
			(effects
				(font
					(size 1.016 1.016)
					(thickness 0.1524)
				)
			)
		)
		(duplicate_pad_numbers_are_jumpers no)
		(fp_poly
			(pts
				(arc
					(start 0.3556 0)
					(mid -0.3556 0)
					(end 0.3556 0)
				)
			)
			(stroke
				(width 0)
				(type default)
			)
			(fill no)
			(layer "F.CrtYd")
		)
		(fp_poly
			(pts
				(arc
					(start 0.6096 0)
					(mid -0.6096 0)
					(end 0.6096 0)
				)
			)
			(stroke
				(width 0)
				(type default)
			)
			(fill no)
			(layer "F.Fab")
		)
		(pad "1" smd circle
			(at 0 0)
			(size 0.7112 0.7112)
			(layers "F.Cu" "F.Mask" "F.Paste")
			(net "TP_BMC_GPIOM5")
		)
	)
	(footprint ""
		(layer "F.Cu")
		(at 206.206852 -111.64316)
		(property "Reference" "PC226"
			(at 0 0 0)
			(layer "F.SilkS")
			(hide yes)
			(effects
				(font
					(size 1.27 1.27)
				)
			)
		)
		(property "Value" "SC22U25V5MX-GP"
			(at -0.0762 -6.1214 0)
			(unlocked yes)
			(layer "F.Fab")
			(hide yes)
			(effects
				(font
					(size 1.016 1.016)
					(thickness 0.1524)
				)
			)
		)
		(property "Device Type" "C805H58"
			(at -0.0762 -8.1534 0)
			(unlocked yes)
			(layer "F.Fab")
			(hide yes)
			(effects
				(font
					(size 1.016 1.016)
					(thickness 0.1524)
				)
			)
		)
		(duplicate_pad_numbers_are_jumpers no)
		(fp_line
			(start 0.635 0)
			(end -0.635 0)
			(stroke
				(width 0.508)
				(type default)
			)
			(layer "F.SilkS")
		)
		(fp_rect
			(start -0.9652 1.778)
			(end 0.9652 -1.778)
			(stroke
				(width 0)
				(type default)
			)
			(fill no)
			(layer "F.CrtYd")
		)
		(fp_poly
			(pts
				(xy -0.9652 -1.778) (xy 0.9652 -1.778) (xy 0.9652 1.778) (xy -0.9652 1.778)
			)
			(stroke
				(width 0)
				(type default)
			)
			(fill no)
			(layer "F.Fab")
		)
		(pad "1" smd rect
			(at 0 -0.9652)
			(size 1.397 1.143)
			(layers "F.Cu" "F.Mask" "F.Paste")
			(net "P1V5_E_VIN")
		)
		(pad "2" smd rect
			(at 0 0.9652)
			(size 1.397 1.143)
			(layers "F.Cu" "F.Mask" "F.Paste")
			(net "GND")
		)
	)
)
